# TIMECARD (Time Appliance Project (Time Card)) — schematic netlist excerpt (pin names and nets, part order shuffled) for the footprints in the layout excerpt that follows; sources: Cadence DE-HDL packaged netlist, KiCad conversion of R4006-B0001-02_R01.brd

U34  TPS3808G18DBVR_SOT23_6  pkg SOT23_6  page 9
  \reset*\  = FPGA_IN_RST_DLY_N
  GND  = SG
  \mr*\  = PCIE_PERST_N
  CT  = UNNAMED_3_RESISTOR_I151_2
  SENSE  = XP3R3V_FPGA
  VDD  = XP3R3V_FPGA

(kicad_pcb
	(version 20260206)
	(generator "pcbnew")
	(generator_version "10.0")
	(general
		(thickness 1.6)
		(legacy_teardrops no)
	)
	(paper "A4")
	(title_block
		(title "timecard-production-celestica-r4006 — R4006-B0001-02_R01.brd")
		(comment 1 "Time Appliance Project (Time Card) / footprint 546 of 1113 (U34), pads 1-6 of 6")
	)
	(layers
		(0 "F.Cu" signal "TOP")
		(4 "In1.Cu" signal "L02_GND1")
		(6 "In2.Cu" signal "L03_SIG1")
		(8 "In3.Cu" signal "L04_GND2")
		(10 "In4.Cu" signal "L05_VCC1")
		(12 "In5.Cu" signal "L06_VCC2")
		(14 "In6.Cu" signal "L07_GND3")
		(16 "In7.Cu" signal "L08_SIG2")
		(18 "In8.Cu" signal "L09_GND4")
		(2 "B.Cu" signal "BOTTOM")
		(9 "F.Adhes" user "F.Adhesive")
		(11 "B.Adhes" user "B.Adhesive")
		(13 "F.Paste" user "Package Geometry/Pastemask Top")
		(15 "B.Paste" user "Package Geometry/Pastemask Bottom")
		(5 "F.SilkS" user "Ref Des/Silkscreen Top")
		(7 "B.SilkS" user "Ref Des/Silkscreen Bottom")
		(1 "F.Mask" user "Board Geometry/Soldermask Top")
		(3 "B.Mask" user "Board Geometry/Soldermask Bottom")
		(17 "Dwgs.User" user "User.Drawings")
		(19 "Cmts.User" user "User.Comments")
		(21 "Eco1.User" user "User.Eco1")
		(23 "Eco2.User" user "User.Eco2")
		(25 "Edge.Cuts" user "Board Geometry/Outline")
		(27 "Margin" user)
		(31 "F.CrtYd" user "Package Geometry/Place Bound Top")
		(29 "B.CrtYd" user "Package Geometry/Place Bound Bottom")
		(35 "F.Fab" user "Ref Des/Assembly Top")
		(33 "B.Fab" user "Ref Des/Assembly Bottom")
	)
	(footprint ""
		(layer "F.Cu")
		(at 93.853 -65.278 -90)
		(property "Reference" "U34"
			(at -1.23063 -3.683 0)
			(unlocked yes)
			(layer "F.SilkS")
			(effects
				(font
					(size 0.7874 0.5842)
					(thickness 0.1524)
				)
			)
		)
		(property "Value" ""
			(at 0 0 270)
			(layer "F.Fab")
			(effects
				(font
					(size 1.27 1.27)
				)
			)
		)
		(property "Device Type" "TPS3808G18DBVR_SOT23_6-G222-00A"
			(at 0.1016 2.54127 270)
			(unlocked yes)
			(layer "F.Fab")
			(hide yes)
			(effects
				(font
					(size 0.7874 0.5842)
					(thickness 0.1524)
				)
			)
		)
		(property "User Part Number" "PARTNUM*"
			(at 0.1016 3.45567 270)
			(unlocked yes)
			(layer "Cmts.User")
			(hide yes)
			(effects
				(font
					(size 0.7874 0.5842)
					(thickness 0.1524)
				)
			)
		)
		(duplicate_pad_numbers_are_jumpers no)
		(pad "1" smd rect
			(at -1.4351 -0.94996)
			(size 0.508 1.1938)
			(layers "F.Cu" "F.Mask" "F.Paste")
			(net "FPGA_IN_RST_DLY_N")
		)
		(pad "2" smd rect
			(at -1.4351 0)
			(size 0.508 1.1938)
			(layers "F.Cu" "F.Mask" "F.Paste")
			(net "SG")
		)
		(pad "3" smd rect
			(at -1.4351 0.94996)
			(size 0.508 1.1938)
			(layers "F.Cu" "F.Mask" "F.Paste")
			(net "PCIE_PERST_N")
		)
		(pad "4" smd rect
			(at 1.4351 0.94996)
			(size 0.508 1.1938)
			(layers "F.Cu" "F.Mask" "F.Paste")
			(net "UNNAMED_3_RESISTOR_I151_2")
		)
		(pad "5" smd rect
			(at 1.4351 0)
			(size 0.508 1.1938)
			(layers "F.Cu" "F.Mask" "F.Paste")
			(net "XP3R3V_FPGA")
		)
		(pad "6" smd rect
			(at 1.4351 -0.94996)
			(size 0.508 1.1938)
			(layers "F.Cu" "F.Mask" "F.Paste")
			(net "XP3R3V_FPGA")
		)
	)
)
